(kicad_pcb
	(version 20241229)
	(generator "pcbnew")
	(generator_version "9.0")
	(general
		(thickness 1.711)
		(legacy_teardrops no)
	)
	(paper "A4")
	(title_block
		(title "Antmicro Baseboard for Jetson AGX Thor")
		(date "2026-02-18")
		(rev "1.1.0")
		(company "Antmicro Ltd")
		(comment 1 "www.antmicro.com")
		(comment 9 "footprints 236-240 of 1170")
	)
	(layers
		(0 "F.Cu" signal)
		(4 "In1.Cu" signal)
		(6 "In2.Cu" signal)
		(8 "In3.Cu" signal)
		(10 "In4.Cu" jumper)
		(12 "In5.Cu" signal)
		(14 "In6.Cu" signal)
		(16 "In7.Cu" signal)
		(18 "In8.Cu" signal)
		(2 "B.Cu" signal)
		(9 "F.Adhes" user "F.Adhesive")
		(11 "B.Adhes" user "B.Adhesive")
		(13 "F.Paste" user)
		(15 "B.Paste" user)
		(5 "F.SilkS" user "F.Silkscreen")
		(7 "B.SilkS" user "B.Silkscreen")
		(1 "F.Mask" user)
		(3 "B.Mask" user)
		(17 "Dwgs.User" user "User.Drawings")
		(19 "Cmts.User" user "User.Comments")
		(21 "Eco1.User" user "User.Eco1")
		(23 "Eco2.User" user "User.Eco2")
		(25 "Edge.Cuts" user)
		(27 "Margin" user)
		(31 "F.CrtYd" user "F.Courtyard")
		(29 "B.CrtYd" user "B.Courtyard")
		(35 "F.Fab" user)
		(33 "B.Fab" user)
	)
	(footprint "antmicro-footprints:C_0805_2012Metric"
		(layer "F.Cu")
		(at 173.19 79.81 90)
		(descr "Capacitor SMD 0805")
		(tags "capacitor SMD 0805")
		(property "Reference" "C296"
			(at -4.67 0.31 90)
			(layer "F.SilkS")
			(effects
				(font
					(size 0.7 0.7)
					(thickness 0.15)
				)
				(justify left bottom)
			)
		)
		(property "Value" "C_22u_25V_0805"
			(at -2.055717 1.963152 90)
			(layer "F.Fab")
			(effects
				(font
					(size 0.7 0.7)
					(thickness 0.15)
				)
				(justify left bottom)
			)
		)
		(property "Datasheet" "https://product.samsungsem.com/mlcc/CL21A226MAYNNN.do"
			(at 0 0 90)
			(layer "F.Fab")
			(hide yes)
			(effects
				(font
					(size 1.27 1.27)
					(thickness 0.15)
				)
			)
		)
		(property "Description" "SMT Multilayer Ceramic Capacitor, 22uF, +/-20%, 25V, X5R, 0805 [2012 Metric]"
			(at 0 0 90)
			(layer "F.Fab")
			(hide yes)
			(effects
				(font
					(size 1.27 1.27)
					(thickness 0.15)
				)
			)
		)
		(property "MPN" "CL21A226MAYNNNE"
			(at 0 0 90)
			(unlocked yes)
			(layer "F.Fab")
			(hide yes)
			(effects
				(font
					(size 1 1)
					(thickness 0.15)
				)
			)
		)
		(property "Manufacturer" "Samsung Electro-Mechanics"
			(at 0 0 90)
			(unlocked yes)
			(layer "F.Fab")
			(hide yes)
			(effects
				(font
					(size 1 1)
					(thickness 0.15)
				)
			)
		)
		(property "License" "Apache-2.0"
			(at 0 0 90)
			(unlocked yes)
			(layer "F.Fab")
			(hide yes)
			(effects
				(font
					(size 1 1)
					(thickness 0.15)
				)
			)
		)
		(property "Author" "Antmicro"
			(at 0 0 90)
			(unlocked yes)
			(layer "F.Fab")
			(hide yes)
			(effects
				(font
					(size 1 1)
					(thickness 0.15)
				)
			)
		)
		(property "Val" "22u"
			(at 0 0 90)
			(unlocked yes)
			(layer "F.Fab")
			(hide yes)
			(effects
				(font
					(size 1 1)
					(thickness 0.15)
				)
			)
		)
		(property "Voltage" "25V"
			(at 0 0 90)
			(unlocked yes)
			(layer "F.Fab")
			(hide yes)
			(effects
				(font
					(size 1 1)
					(thickness 0.15)
				)
			)
		)
		(property "Dielectric" "X5R"
			(at 0 0 90)
			(unlocked yes)
			(layer "F.Fab")
			(hide yes)
			(effects
				(font
					(size 1 1)
					(thickness 0.15)
				)
			)
		)
		(property "Public" "False"
			(at 0 0 90)
			(unlocked yes)
			(layer "F.Fab")
			(hide yes)
			(effects
				(font
					(size 1 1)
					(thickness 0.15)
				)
			)
		)
		(component_classes
			(class "DCDC_20V")
		)
		(sheetname "/DCDC/")
		(sheetfile "dcdc.kicad_sch")
		(attr smd)
		(fp_line
			(start -0.3 -0.7)
			(end 0.3 -0.7)
			(stroke
				(width 0.15)
				(type solid)
			)
			(layer "F.SilkS")
		)
		(fp_line
			(start -0.3 0.7)
			(end 0.3 0.7)
			(stroke
				(width 0.15)
				(type solid)
			)
			(layer "F.SilkS")
		)
		(fp_rect
			(start 1.95 -0.9)
			(end -1.95 0.9)
			(stroke
				(width 0.05)
				(type default)
			)
			(fill no)
			(layer "F.CrtYd")
		)
		(fp_rect
			(start -0.95 -0.675)
			(end 0.95 0.675)
			(stroke
				(width 0.15)
				(type solid)
			)
			(fill no)
			(layer "F.Fab")
		)
		(fp_text user "${REFERENCE}"
			(at -1.9 3.947 90)
			(layer "F.Fab")
			(effects
				(font
					(size 0.7 0.7)
					(thickness 0.15)
				)
				(justify left bottom)
			)
		)
		(fp_text user "License: Apache-2.0"
			(at -1.9 4.947 90)
			(layer "F.Fab")
			(effects
				(font
					(size 0.7 0.7)
					(thickness 0.15)
				)
				(justify left bottom)
			)
		)
		(fp_text user "Author: Antmicro"
			(at -1.9 5.947 90)
			(layer "F.Fab")
			(effects
				(font
					(size 0.7 0.7)
					(thickness 0.15)
				)
				(justify left bottom)
			)
		)
		(pad "1" smd roundrect
			(at -1.1 0 90)
			(size 1.2 1.3)
			(layers "F.Cu" "F.Mask" "F.Paste")
			(roundrect_rratio 0.25)
			(net 1 "GND")
			(pintype "passive")
		)
		(pad "2" smd roundrect
			(at 1.1 0 90)
			(size 1.2 1.3)
			(layers "F.Cu" "F.Mask" "F.Paste")
			(roundrect_rratio 0.25)
			(net 1105 "/DCDC/20V_OUT")
			(pintype "passive")
		)
	)
	(footprint "antmicro-footprints:R_0402_1005Metric"
		(layer "F.Cu")
		(at 198.25 84 90)
		(descr "Resistor SMD 0402")
		(tags "resistor SMD 0402")
		(property "Reference" "R93"
			(at -0.9 -0.55 90)
			(layer "F.SilkS")
			(effects
				(font
					(size 0.7 0.7)
					(thickness 0.15)
				)
				(justify left bottom)
			)
		)
		(property "Value" "R_0R_0402"
			(at -1.011843 1.772047 90)
			(layer "F.Fab")
			(effects
				(font
					(size 0.7 0.7)
					(thickness 0.15)
				)
				(justify left bottom)
			)
		)
		(property "Datasheet" "https://industrial.panasonic.com/cdbs/www-data/pdf/RDA0000/AOA0000C301.pdf"
			(at 0 0 90)
			(layer "F.Fab")
			(hide yes)
			(effects
				(font
					(size 1.27 1.27)
					(thickness 0.15)
				)
			)
		)
		(property "Description" "SMD Chip Resistor, Jumper, 0 ohm, 100 mW, 0402 [1005 Metric], Thick Film, General Purpose"
			(at 0 0 90)
			(layer "F.Fab")
			(hide yes)
			(effects
				(font
					(size 1.27 1.27)
					(thickness 0.15)
				)
			)
		)
		(property "Manufacturer" "Panasonic"
			(at 0 0 90)
			(unlocked yes)
			(layer "F.Fab")
			(hide yes)
			(effects
				(font
					(size 1 1)
					(thickness 0.15)
				)
			)
		)
		(property "MPN" "ERJ2GE0R00X"
			(at 0 0 90)
			(unlocked yes)
			(layer "F.Fab")
			(hide yes)
			(effects
				(font
					(size 1 1)
					(thickness 0.15)
				)
			)
		)
		(property "Val" "0R"
			(at 0 0 90)
			(unlocked yes)
			(layer "F.Fab")
			(hide yes)
			(effects
				(font
					(size 1 1)
					(thickness 0.15)
				)
			)
		)
		(property "License" "Apache-2.0"
			(at 0 0 90)
			(unlocked yes)
			(layer "F.Fab")
			(hide yes)
			(effects
				(font
					(size 1 1)
					(thickness 0.15)
				)
			)
		)
		(property "Author" "Antmicro"
			(at 0 0 90)
			(unlocked yes)
			(layer "F.Fab")
			(hide yes)
			(effects
				(font
					(size 1 1)
					(thickness 0.15)
				)
			)
		)
		(property "Tolerance" "~"
			(at 0 0 90)
			(unlocked yes)
			(layer "F.Fab")
			(hide yes)
			(effects
				(font
					(size 1 1)
					(thickness 0.15)
				)
			)
		)
		(property "Current" "1A"
			(at 0 0 90)
			(unlocked yes)
			(layer "F.Fab")
			(hide yes)
			(effects
				(font
					(size 1 1)
					(thickness 0.15)
				)
			)
		)
		(sheetname "/USB Debug, PD/")
		(sheetfile "usb_debug_pd.kicad_sch")
		(attr smd)
		(fp_rect
			(start -0.925 -0.47)
			(end 0.925 0.47)
			(stroke
				(width 0.05)
				(type default)
			)
			(fill no)
			(layer "F.CrtYd")
		)
		(fp_rect
			(start -0.5 -0.25)
			(end 0.5 0.25)
			(stroke
				(width 0.15)
				(type solid)
			)
			(fill no)
			(layer "F.Fab")
		)
		(fp_text user "License: Apache-2.0"
			(at -0.95 5.169 90)
			(layer "F.Fab")
			(effects
				(font
					(size 0.7 0.7)
					(thickness 0.15)
				)
				(justify left bottom)
			)
		)
		(fp_text user "Author: Antmicro"
			(at -0.95 4.169 90)
			(layer "F.Fab")
			(effects
				(font
					(size 0.7 0.7)
					(thickness 0.15)
				)
				(justify left bottom)
			)
		)
		(fp_text user "${REFERENCE}"
			(at -0.95 3.168 90)
			(layer "F.Fab")
			(effects
				(font
					(size 0.7 0.7)
					(thickness 0.15)
				)
				(justify left bottom)
			)
		)
		(pad "1" smd roundrect
			(at -0.48 0 90)
			(size 0.59 0.64)
			(layers "F.Cu" "F.Mask" "F.Paste")
			(roundrect_rratio 0.25)
			(net 1 "GND")
			(pintype "passive")
		)
		(pad "2" smd roundrect
			(at 0.48 0 90)
			(size 0.59 0.64)
			(layers "F.Cu" "F.Mask" "F.Paste")
			(roundrect_rratio 0.25)
			(net 933 "/USB Debug, PD/PDC_RESET")
			(pintype "passive")
		)
	)
	(footprint "antmicro-footprints:R_0603_1608Metric"
		(layer "F.Cu")
		(at 79.2 132)
		(descr "Resistor SMD 0603")
		(tags "resistor SMD 0603")
		(property "Reference" "R248"
			(at 1.3 0.3 0)
			(layer "F.SilkS")
			(effects
				(font
					(size 0.7 0.7)
					(thickness 0.15)
				)
				(justify left bottom)
			)
		)
		(property "Value" "R_0R_22.4A_0603"
			(at 0 1.6 0)
			(layer "F.Fab")
			(effects
				(font
					(size 0.7 0.7)
					(thickness 0.15)
				)
				(justify left bottom)
			)
		)
		(property "Datasheet" "https://fscdn.rohm.com/en/products/databook/datasheet/passive/resistor/chip_resistor/pmr-jpw-e.pdf"
			(at 0 0 0)
			(layer "F.Fab")
			(hide yes)
			(effects
				(font
					(size 1.27 1.27)
					(thickness 0.15)
				)
			)
		)
		(property "Description" "SMD Chip Resistor"
			(at 0 0 0)
			(layer "F.Fab")
			(hide yes)
			(effects
				(font
					(size 1.27 1.27)
					(thickness 0.15)
				)
			)
		)
		(property "MPN" "PMR03EZPJ000"
			(at 0 0 0)
			(unlocked yes)
			(layer "F.Fab")
			(hide yes)
			(effects
				(font
					(size 1 1)
					(thickness 0.15)
				)
			)
		)
		(property "Manufacturer" "ROHM Semiconductor"
			(at 0 0 0)
			(unlocked yes)
			(layer "F.Fab")
			(hide yes)
			(effects
				(font
					(size 1 1)
					(thickness 0.15)
				)
			)
		)
		(property "Val" "0R"
			(at 0 0 0)
			(unlocked yes)
			(layer "F.Fab")
			(hide yes)
			(effects
				(font
					(size 1 1)
					(thickness 0.15)
				)
			)
		)
		(property "Max. Curr." "22.4A"
			(at 0 0 0)
			(unlocked yes)
			(layer "F.Fab")
			(hide yes)
			(effects
				(font
					(size 1 1)
					(thickness 0.15)
				)
			)
		)
		(property "Author" "Antmicro"
			(at 0 0 0)
			(unlocked yes)
			(layer "F.Fab")
			(hide yes)
			(effects
				(font
					(size 1 1)
					(thickness 0.15)
				)
			)
		)
		(property "License" "Apache-2.0"
			(at 0 0 0)
			(unlocked yes)
			(layer "F.Fab")
			(hide yes)
			(effects
				(font
					(size 1 1)
					(thickness 0.15)
				)
			)
		)
		(property "Tolerance" "template_tolerance"
			(at 0 0 0)
			(unlocked yes)
			(layer "F.Fab")
			(hide yes)
			(effects
				(font
					(size 1 1)
					(thickness 0.15)
				)
			)
		)
		(sheetname "/Expansion connector/")
		(sheetfile "expansion_connector.kicad_sch")
		(attr smd exclude_from_pos_files exclude_from_bom dnp)
		(fp_line
			(start -0.15 -0.4)
			(end 0.15 -0.4)
			(stroke
				(width 0.15)
				(type solid)
			)
			(layer "F.SilkS")
		)
		(fp_line
			(start -0.15 0.4)
			(end 0.15 0.4)
			(stroke
				(width 0.15)
				(type solid)
			)
			(layer "F.SilkS")
		)
		(fp_poly
			(pts
				(xy -1.25 -0.65) (xy -1.25 0.65) (xy 1.25 0.65) (xy 1.25 -0.65)
			)
			(stroke
				(width 0.05)
				(type solid)
			)
			(fill no)
			(layer "F.CrtYd")
		)
		(fp_poly
			(pts
				(xy -0.8 -0.4) (xy -0.8 0.4) (xy 0.8 0.4) (xy 0.8 -0.4)
			)
			(stroke
				(width 0.15)
				(type solid)
			)
			(fill no)
			(layer "F.Fab")
		)
		(fp_text user "${REFERENCE}"
			(at -1.25 3.898 0)
			(layer "F.Fab")
			(effects
				(font
					(size 0.7 0.7)
					(thickness 0.15)
				)
				(justify left bottom)
			)
		)
		(fp_text user "Author: Antmicro"
			(at -1.25 4.9 0)
			(layer "F.Fab")
			(effects
				(font
					(size 0.7 0.7)
					(thickness 0.15)
				)
				(justify left bottom)
			)
		)
		(fp_text user "License: Apache-2.0"
			(at -1.249999 5.9 0)
			(layer "F.Fab")
			(effects
				(font
					(size 0.7 0.7)
					(thickness 0.15)
				)
				(justify left bottom)
			)
		)
		(pad "1" smd roundrect
			(at -0.7 0)
			(size 0.8 1)
			(layers "F.Cu" "F.Mask" "F.Paste")
			(roundrect_rratio 0.2)
			(net 295 "/Expansion connector/+V_{ADJ}")
			(pintype "passive")
		)
		(pad "2" smd roundrect
			(at 0.7 0)
			(size 0.8 1)
			(layers "F.Cu" "F.Mask" "F.Paste")
			(roundrect_rratio 0.2)
			(net 11 "+1V8")
			(pintype "passive")
		)
	)
	(footprint "antmicro-footprints:R_0402_1005Metric"
		(layer "F.Cu")
		(at 214.8 120.1 -90)
		(descr "Resistor SMD 0402")
		(tags "resistor SMD 0402")
		(property "Reference" "R80"
			(at -3.055 0.38 90)
			(layer "F.SilkS")
			(effects
				(font
					(size 0.7 0.7)
					(thickness 0.15)
				)
				(justify right top)
			)
		)
		(property "Value" "R_200k_0402"
			(at -1.011843 1.772046 90)
			(layer "F.Fab")
			(effects
				(font
					(size 0.7 0.7)
					(thickness 0.15)
				)
				(justify right top)
			)
		)
		(property "Datasheet" "https://www.bourns.com/docs/product-datasheets/cr.pdf"
			(at 0 0 90)
			(layer "F.Fab")
			(hide yes)
			(effects
				(font
					(size 1.27 1.27)
					(thickness 0.15)
				)
			)
		)
		(property "Description" "SMD Chip Resistor, 200 kohm, ± 1%, 62.5 mW, 0402 [1005 Metric], Thick Film, General Purpose"
			(at 0 0 90)
			(layer "F.Fab")
			(hide yes)
			(effects
				(font
					(size 1.27 1.27)
					(thickness 0.15)
				)
			)
		)
		(property "MPN" "CR0402-FX-2003GLF"
			(at 0 0 270)
			(unlocked yes)
			(layer "F.Fab")
			(hide yes)
			(effects
				(font
					(size 1 1)
					(thickness 0.15)
				)
			)
		)
		(property "Manufacturer" "Bourns"
			(at 0 0 270)
			(unlocked yes)
			(layer "F.Fab")
			(hide yes)
			(effects
				(font
					(size 1 1)
					(thickness 0.15)
				)
			)
		)
		(property "License" "Apache-2.0"
			(at 0 0 270)
			(unlocked yes)
			(layer "F.Fab")
			(hide yes)
			(effects
				(font
					(size 1 1)
					(thickness 0.15)
				)
			)
		)
		(property "Author" "Antmicro"
			(at 0 0 270)
			(unlocked yes)
			(layer "F.Fab")
			(hide yes)
			(effects
				(font
					(size 1 1)
					(thickness 0.15)
				)
			)
		)
		(property "Val" "200k"
			(at 0 0 270)
			(unlocked yes)
			(layer "F.Fab")
			(hide yes)
			(effects
				(font
					(size 1 1)
					(thickness 0.15)
				)
			)
		)
		(property "Tolerance" "1%"
			(at 0 0 270)
			(unlocked yes)
			(layer "F.Fab")
			(hide yes)
			(effects
				(font
					(size 1 1)
					(thickness 0.15)
				)
			)
		)
		(sheetname "/USB Hub/")
		(sheetfile "usb_hub.kicad_sch")
		(attr smd)
		(fp_poly
			(pts
				(xy -0.925 -0.47) (xy 0.925 -0.47) (xy 0.925 0.47) (xy -0.925 0.47)
			)
			(stroke
				(width 0.05)
				(type default)
			)
			(fill no)
			(layer "F.CrtYd")
		)
		(fp_poly
			(pts
				(xy -0.5 -0.25) (xy 0.5 -0.25) (xy 0.5 0.25) (xy -0.5 0.25)
			)
			(stroke
				(width 0.15)
				(type solid)
			)
			(fill no)
			(layer "F.Fab")
		)
		(fp_text user "License: Apache-2.0"
			(at -0.949999 5.169 90)
			(layer "F.Fab")
			(effects
				(font
					(size 0.7 0.7)
					(thickness 0.15)
				)
				(justify right top)
			)
		)
		(fp_text user "Author: Antmicro"
			(at -0.95 4.169 90)
			(layer "F.Fab")
			(effects
				(font
					(size 0.7 0.7)
					(thickness 0.15)
				)
				(justify right top)
			)
		)
		(fp_text user "${REFERENCE}"
			(at -0.95 3.168 90)
			(layer "F.Fab")
			(effects
				(font
					(size 0.7 0.7)
					(thickness 0.15)
				)
				(justify right top)
			)
		)
		(pad "1" smd roundrect
			(at -0.48 0 270)
			(size 0.59 0.64)
			(layers "F.Cu" "F.Mask" "F.Paste")
			(roundrect_rratio 0.25)
			(net 1 "GND")
			(pintype "passive")
		)
		(pad "2" smd roundrect
			(at 0.48 0 270)
			(size 0.59 0.64)
			(layers "F.Cu" "F.Mask" "F.Paste")
			(roundrect_rratio 0.25)
			(net 915 "/USB Hub/CFG_STRAP2")
			(pintype "passive")
		)
	)
	(footprint "antmicro-footprints:C_0805_2012Metric"
		(layer "F.Cu")
		(at 164.09 99.81 90)
		(descr "Capacitor SMD 0805")
		(tags "capacitor SMD 0805")
		(property "Reference" "C258"
			(at -4.595 0.345 90)
			(layer "F.SilkS")
			(effects
				(font
					(size 0.7 0.7)
					(thickness 0.15)
				)
				(justify left bottom)
			)
		)
		(property "Value" "C_22u_25V_0805"
			(at -2.055717 1.963152 90)
			(layer "F.Fab")
			(effects
				(font
					(size 0.7 0.7)
					(thickness 0.15)
				)
				(justify left bottom)
			)
		)
		(property "Datasheet" "https://product.samsungsem.com/mlcc/CL21A226MAYNNN.do"
			(at 0 0 90)
			(layer "F.Fab")
			(hide yes)
			(effects
				(font
					(size 1.27 1.27)
					(thickness 0.15)
				)
			)
		)
		(property "Description" "SMT Multilayer Ceramic Capacitor, 22uF, +/-20%, 25V, X5R, 0805 [2012 Metric]"
			(at 0 0 90)
			(layer "F.Fab")
			(hide yes)
			(effects
				(font
					(size 1.27 1.27)
					(thickness 0.15)
				)
			)
		)
		(property "MPN" "CL21A226MAYNNNE"
			(at 0 0 90)
			(unlocked yes)
			(layer "F.Fab")
			(hide yes)
			(effects
				(font
					(size 1 1)
					(thickness 0.15)
				)
			)
		)
		(property "Manufacturer" "Samsung Electro-Mechanics"
			(at 0 0 90)
			(unlocked yes)
			(layer "F.Fab")
			(hide yes)
			(effects
				(font
					(size 1 1)
					(thickness 0.15)
				)
			)
		)
		(property "License" "Apache-2.0"
			(at 0 0 90)
			(unlocked yes)
			(layer "F.Fab")
			(hide yes)
			(effects
				(font
					(size 1 1)
					(thickness 0.15)
				)
			)
		)
		(property "Author" "Antmicro"
			(at 0 0 90)
			(unlocked yes)
			(layer "F.Fab")
			(hide yes)
			(effects
				(font
					(size 1 1)
					(thickness 0.15)
				)
			)
		)
		(property "Val" "22u"
			(at 0 0 90)
			(unlocked yes)
			(layer "F.Fab")
			(hide yes)
			(effects
				(font
					(size 1 1)
					(thickness 0.15)
				)
			)
		)
		(property "Voltage" "25V"
			(at 0 0 90)
			(unlocked yes)
			(layer "F.Fab")
			(hide yes)
			(effects
				(font
					(size 1 1)
					(thickness 0.15)
				)
			)
		)
		(property "Dielectric" "X5R"
			(at 0 0 90)
			(unlocked yes)
			(layer "F.Fab")
			(hide yes)
			(effects
				(font
					(size 1 1)
					(thickness 0.15)
				)
			)
		)
		(property "Public" "False"
			(at 0 0 90)
			(unlocked yes)
			(layer "F.Fab")
			(hide yes)
			(effects
				(font
					(size 1 1)
					(thickness 0.15)
				)
			)
		)
		(component_classes
			(class "DCDC_SOM")
		)
		(sheetname "/DCDC/")
		(sheetfile "dcdc.kicad_sch")
		(attr smd)
		(fp_line
			(start -0.3 -0.7)
			(end 0.3 -0.7)
			(stroke
				(width 0.15)
				(type solid)
			)
			(layer "F.SilkS")
		)
		(fp_line
			(start -0.3 0.7)
			(end 0.3 0.7)
			(stroke
				(width 0.15)
				(type solid)
			)
			(layer "F.SilkS")
		)
		(fp_rect
			(start 1.95 -0.9)
			(end -1.95 0.9)
			(stroke
				(width 0.05)
				(type default)
			)
			(fill no)
			(layer "F.CrtYd")
		)
		(fp_rect
			(start -0.95 -0.675)
			(end 0.95 0.675)
			(stroke
				(width 0.15)
				(type solid)
			)
			(fill no)
			(layer "F.Fab")
		)
		(fp_text user "License: Apache-2.0"
			(at -1.9 4.947 90)
			(layer "F.Fab")
			(effects
				(font
					(size 0.7 0.7)
					(thickness 0.15)
				)
				(justify left bottom)
			)
		)
		(fp_text user "Author: Antmicro"
			(at -1.9 5.947 90)
			(layer "F.Fab")
			(effects
				(font
					(size 0.7 0.7)
					(thickness 0.15)
				)
				(justify left bottom)
			)
		)
		(fp_text user "${REFERENCE}"
			(at -1.9 3.947 90)
			(layer "F.Fab")
			(effects
				(font
					(size 0.7 0.7)
					(thickness 0.15)
				)
				(justify left bottom)
			)
		)
		(pad "1" smd roundrect
			(at -1.1 0 90)
			(size 1.2 1.3)
			(layers "F.Cu" "F.Mask" "F.Paste")
			(roundrect_rratio 0.25)
			(net 1 "GND")
			(pintype "passive")
		)
		(pad "2" smd roundrect
			(at 1.1 0 90)
			(size 1.2 1.3)
			(layers "F.Cu" "F.Mask" "F.Paste")
			(roundrect_rratio 0.25)
			(net 903 "/DCDC/16V_OUT")
			(pintype "passive")
		)
	)
)
